(kicad_pcb
	(version 20260206)
	(generator "pcbnew")
	(generator_version "10.0")
	(general
		(thickness 1.6)
		(legacy_teardrops no)
	)
	(paper "A4")
	(title_block
		(title "12092022_DA0F0TMDCD0_F0T_Management_Board_D_brd_V3_OCP.brd")
		(comment 1 "Grand Teton / footprints 974-979 of 1440")
	)
	(layers
		(0 "F.Cu" signal "TOP")
		(4 "In1.Cu" signal "GND")
		(6 "In2.Cu" signal "IN1")
		(8 "In3.Cu" signal "GND1")
		(10 "In4.Cu" signal "IN2")
		(12 "In5.Cu" signal "VCC")
		(14 "In6.Cu" signal "VCC1")
		(16 "In7.Cu" signal "IN3")
		(18 "In8.Cu" signal "GND2")
		(20 "In9.Cu" signal "IN4")
		(22 "In10.Cu" signal "GND3")
		(2 "B.Cu" signal "BOTTOM")
		(9 "F.Adhes" user "F.Adhesive")
		(11 "B.Adhes" user "B.Adhesive")
		(13 "F.Paste" user "Package Geometry/Pastemask Top")
		(15 "B.Paste" user "Package Geometry/Pastemask Bottom")
		(5 "F.SilkS" user "Ref Des/Silkscreen Top")
		(7 "B.SilkS" user "Ref Des/Silkscreen Bottom")
		(1 "F.Mask" user "Board Geometry/Soldermask Top")
		(3 "B.Mask" user "Board Geometry/Soldermask Bottom")
		(17 "Dwgs.User" user "User.Drawings")
		(19 "Cmts.User" user "User.Comments")
		(21 "Eco1.User" user "User.Eco1")
		(23 "Eco2.User" user "User.Eco2")
		(25 "Edge.Cuts" user "Board Geometry/Outline")
		(27 "Margin" user)
		(31 "F.CrtYd" user "Package Geometry/Place Bound Top")
		(29 "B.CrtYd" user "Package Geometry/Place Bound Bottom")
		(35 "F.Fab" user "Ref Des/Assembly Top")
		(33 "B.Fab" user "Ref Des/Assembly Bottom")
	)
	(footprint ""
		(layer "B.Cu")
		(at 11.2776 -106.3752 -90)
		(property "Reference" "R847"
			(at 0 0 90)
			(layer "B.SilkS")
			(hide yes)
			(effects
				(font
					(size 1.27 1.27)
				)
				(justify mirror)
			)
		)
		(property "Value" ""
			(at 0 0 90)
			(layer "B.Fab")
			(effects
				(font
					(size 1.27 1.27)
				)
				(justify mirror)
			)
		)
		(duplicate_pad_numbers_are_jumpers no)
		(fp_line
			(start -0.7874 0.4064)
			(end 0.7874 0.4064)
			(stroke
				(width 0.1524)
				(type default)
			)
			(layer "B.SilkS")
		)
		(fp_line
			(start 0.7874 0.4064)
			(end 0.7874 -0.4064)
			(stroke
				(width 0.1524)
				(type default)
			)
			(layer "B.SilkS")
		)
		(fp_line
			(start -0.7874 -0.4064)
			(end -0.7874 0.4064)
			(stroke
				(width 0.1524)
				(type default)
			)
			(layer "B.SilkS")
		)
		(fp_line
			(start 0.7874 -0.4064)
			(end -0.7874 -0.4064)
			(stroke
				(width 0.1524)
				(type default)
			)
			(layer "B.SilkS")
		)
		(fp_line
			(start -0.67945 0.3048)
			(end -0.120396 0.3048)
			(stroke
				(width 0.1)
				(type default)
			)
			(layer "B.Fab")
		)
		(fp_line
			(start -0.120396 0.3048)
			(end -0.120396 0.2794)
			(stroke
				(width 0.1)
				(type default)
			)
			(layer "B.Fab")
		)
		(fp_line
			(start 0.12065 0.3048)
			(end 0.67945 0.3048)
			(stroke
				(width 0.1)
				(type default)
			)
			(layer "B.Fab")
		)
		(fp_line
			(start 0.67945 0.3048)
			(end 0.67945 -0.305054)
			(stroke
				(width 0.1)
				(type default)
			)
			(layer "B.Fab")
		)
		(fp_line
			(start -0.120396 0.2794)
			(end 0.12065 0.2794)
			(stroke
				(width 0.1)
				(type default)
			)
			(layer "B.Fab")
		)
		(fp_line
			(start 0.12065 0.2794)
			(end 0.12065 0.3048)
			(stroke
				(width 0.1)
				(type default)
			)
			(layer "B.Fab")
		)
		(fp_line
			(start -0.12065 -0.2794)
			(end -0.12065 -0.3048)
			(stroke
				(width 0.1)
				(type default)
			)
			(layer "B.Fab")
		)
		(fp_line
			(start 0.12065 -0.2794)
			(end -0.12065 -0.2794)
			(stroke
				(width 0.1)
				(type default)
			)
			(layer "B.Fab")
		)
		(fp_line
			(start -0.67945 -0.3048)
			(end -0.67945 0.3048)
			(stroke
				(width 0.1)
				(type default)
			)
			(layer "B.Fab")
		)
		(fp_line
			(start -0.12065 -0.3048)
			(end -0.67945 -0.3048)
			(stroke
				(width 0.1)
				(type default)
			)
			(layer "B.Fab")
		)
		(fp_line
			(start 0.12065 -0.305054)
			(end 0.12065 -0.2794)
			(stroke
				(width 0.1)
				(type default)
			)
			(layer "B.Fab")
		)
		(fp_line
			(start 0.67945 -0.305054)
			(end 0.12065 -0.305054)
			(stroke
				(width 0.1)
				(type default)
			)
			(layer "B.Fab")
		)
		(pad "1" smd circle
			(at 0.40005 0 90)
			(size 0 0)
			(layers "B.Cu" "B.Mask" "B.Paste")
			(net "PCH_BEEP_LED")
		)
		(pad "2" smd circle
			(at -0.40005 0 90)
			(size 0 0)
			(layers "B.Cu" "B.Mask" "B.Paste")
			(net "FM_PCH_BEEP_LED")
		)
	)
	(footprint ""
		(layer "B.Cu")
		(at 29.464 -91.059 180)
		(property "Reference" "R586"
			(at 0 0 0)
			(layer "B.SilkS")
			(hide yes)
			(effects
				(font
					(size 1.27 1.27)
				)
				(justify mirror)
			)
		)
		(property "Value" ""
			(at 0 0 0)
			(layer "B.Fab")
			(effects
				(font
					(size 1.27 1.27)
				)
				(justify mirror)
			)
		)
		(duplicate_pad_numbers_are_jumpers no)
		(fp_line
			(start 0.7874 0.4064)
			(end 0.7874 -0.4064)
			(stroke
				(width 0.1524)
				(type default)
			)
			(layer "B.SilkS")
		)
		(fp_line
			(start 0.7874 -0.4064)
			(end -0.7874 -0.4064)
			(stroke
				(width 0.1524)
				(type default)
			)
			(layer "B.SilkS")
		)
		(fp_line
			(start -0.7874 0.4064)
			(end 0.7874 0.4064)
			(stroke
				(width 0.1524)
				(type default)
			)
			(layer "B.SilkS")
		)
		(fp_line
			(start -0.7874 -0.4064)
			(end -0.7874 0.4064)
			(stroke
				(width 0.1524)
				(type default)
			)
			(layer "B.SilkS")
		)
		(fp_line
			(start 0.67945 0.3048)
			(end 0.67945 -0.305054)
			(stroke
				(width 0.1)
				(type default)
			)
			(layer "B.Fab")
		)
		(fp_line
			(start 0.67945 -0.305054)
			(end 0.12065 -0.305054)
			(stroke
				(width 0.1)
				(type default)
			)
			(layer "B.Fab")
		)
		(fp_line
			(start 0.12065 0.3048)
			(end 0.67945 0.3048)
			(stroke
				(width 0.1)
				(type default)
			)
			(layer "B.Fab")
		)
		(fp_line
			(start 0.12065 0.2794)
			(end 0.12065 0.3048)
			(stroke
				(width 0.1)
				(type default)
			)
			(layer "B.Fab")
		)
		(fp_line
			(start 0.12065 -0.2794)
			(end -0.12065 -0.2794)
			(stroke
				(width 0.1)
				(type default)
			)
			(layer "B.Fab")
		)
		(fp_line
			(start 0.12065 -0.305054)
			(end 0.12065 -0.2794)
			(stroke
				(width 0.1)
				(type default)
			)
			(layer "B.Fab")
		)
		(fp_line
			(start -0.120396 0.3048)
			(end -0.120396 0.2794)
			(stroke
				(width 0.1)
				(type default)
			)
			(layer "B.Fab")
		)
		(fp_line
			(start -0.120396 0.2794)
			(end 0.12065 0.2794)
			(stroke
				(width 0.1)
				(type default)
			)
			(layer "B.Fab")
		)
		(fp_line
			(start -0.12065 -0.2794)
			(end -0.12065 -0.3048)
			(stroke
				(width 0.1)
				(type default)
			)
			(layer "B.Fab")
		)
		(fp_line
			(start -0.12065 -0.3048)
			(end -0.67945 -0.3048)
			(stroke
				(width 0.1)
				(type default)
			)
			(layer "B.Fab")
		)
		(fp_line
			(start -0.67945 0.3048)
			(end -0.120396 0.3048)
			(stroke
				(width 0.1)
				(type default)
			)
			(layer "B.Fab")
		)
		(fp_line
			(start -0.67945 -0.3048)
			(end -0.67945 0.3048)
			(stroke
				(width 0.1)
				(type default)
			)
			(layer "B.Fab")
		)
		(pad "1" smd circle
			(at 0.40005 0)
			(size 0 0)
			(layers "B.Cu" "B.Mask" "B.Paste")
			(net "P3V3_AUX")
		)
		(pad "2" smd circle
			(at -0.40005 0)
			(size 0 0)
			(layers "B.Cu" "B.Mask" "B.Paste")
			(net "BMC_CPLD_GPIO_2")
		)
	)
	(footprint ""
		(layer "B.Cu")
		(at 55.8546 -66.0146 -90)
		(property "Reference" "R180"
			(at 0 0 90)
			(layer "B.SilkS")
			(hide yes)
			(effects
				(font
					(size 1.27 1.27)
				)
				(justify mirror)
			)
		)
		(property "Value" ""
			(at 0 0 90)
			(layer "B.Fab")
			(effects
				(font
					(size 1.27 1.27)
				)
				(justify mirror)
			)
		)
		(duplicate_pad_numbers_are_jumpers no)
		(fp_line
			(start -0.7874 0.4064)
			(end 0.7874 0.4064)
			(stroke
				(width 0.1524)
				(type default)
			)
			(layer "B.SilkS")
		)
		(fp_line
			(start 0.7874 0.4064)
			(end 0.7874 -0.4064)
			(stroke
				(width 0.1524)
				(type default)
			)
			(layer "B.SilkS")
		)
		(fp_line
			(start -0.7874 -0.4064)
			(end -0.7874 0.4064)
			(stroke
				(width 0.1524)
				(type default)
			)
			(layer "B.SilkS")
		)
		(fp_line
			(start 0.7874 -0.4064)
			(end -0.7874 -0.4064)
			(stroke
				(width 0.1524)
				(type default)
			)
			(layer "B.SilkS")
		)
		(fp_line
			(start -0.67945 0.3048)
			(end -0.120396 0.3048)
			(stroke
				(width 0.1)
				(type default)
			)
			(layer "B.Fab")
		)
		(fp_line
			(start -0.120396 0.3048)
			(end -0.120396 0.2794)
			(stroke
				(width 0.1)
				(type default)
			)
			(layer "B.Fab")
		)
		(fp_line
			(start 0.12065 0.3048)
			(end 0.67945 0.3048)
			(stroke
				(width 0.1)
				(type default)
			)
			(layer "B.Fab")
		)
		(fp_line
			(start 0.67945 0.3048)
			(end 0.67945 -0.305054)
			(stroke
				(width 0.1)
				(type default)
			)
			(layer "B.Fab")
		)
		(fp_line
			(start -0.120396 0.2794)
			(end 0.12065 0.2794)
			(stroke
				(width 0.1)
				(type default)
			)
			(layer "B.Fab")
		)
		(fp_line
			(start 0.12065 0.2794)
			(end 0.12065 0.3048)
			(stroke
				(width 0.1)
				(type default)
			)
			(layer "B.Fab")
		)
		(fp_line
			(start -0.12065 -0.2794)
			(end -0.12065 -0.3048)
			(stroke
				(width 0.1)
				(type default)
			)
			(layer "B.Fab")
		)
		(fp_line
			(start 0.12065 -0.2794)
			(end -0.12065 -0.2794)
			(stroke
				(width 0.1)
				(type default)
			)
			(layer "B.Fab")
		)
		(fp_line
			(start -0.67945 -0.3048)
			(end -0.67945 0.3048)
			(stroke
				(width 0.1)
				(type default)
			)
			(layer "B.Fab")
		)
		(fp_line
			(start -0.12065 -0.3048)
			(end -0.67945 -0.3048)
			(stroke
				(width 0.1)
				(type default)
			)
			(layer "B.Fab")
		)
		(fp_line
			(start 0.12065 -0.305054)
			(end 0.12065 -0.2794)
			(stroke
				(width 0.1)
				(type default)
			)
			(layer "B.Fab")
		)
		(fp_line
			(start 0.67945 -0.305054)
			(end 0.12065 -0.305054)
			(stroke
				(width 0.1)
				(type default)
			)
			(layer "B.Fab")
		)
		(pad "1" smd circle
			(at 0.40005 0 90)
			(size 0 0)
			(layers "B.Cu" "B.Mask" "B.Paste")
			(net "SPI_BMC_MISO_IO1_R")
		)
		(pad "2" smd circle
			(at -0.40005 0 90)
			(size 0 0)
			(layers "B.Cu" "B.Mask" "B.Paste")
			(net "SPI_BMC_BOOT_MISO")
		)
	)
	(footprint ""
		(layer "B.Cu")
		(at 85.281262 -44.427394 180)
		(property "Reference" "R358"
			(at 0 0 0)
			(layer "B.SilkS")
			(hide yes)
			(effects
				(font
					(size 1.27 1.27)
				)
				(justify mirror)
			)
		)
		(property "Value" ""
			(at 0 0 0)
			(layer "B.Fab")
			(effects
				(font
					(size 1.27 1.27)
				)
				(justify mirror)
			)
		)
		(duplicate_pad_numbers_are_jumpers no)
		(fp_line
			(start 0.7874 0.4064)
			(end 0.7874 -0.4064)
			(stroke
				(width 0.1524)
				(type default)
			)
			(layer "B.SilkS")
		)
		(fp_line
			(start 0.7874 -0.4064)
			(end -0.7874 -0.4064)
			(stroke
				(width 0.1524)
				(type default)
			)
			(layer "B.SilkS")
		)
		(fp_line
			(start -0.7874 0.4064)
			(end 0.7874 0.4064)
			(stroke
				(width 0.1524)
				(type default)
			)
			(layer "B.SilkS")
		)
		(fp_line
			(start -0.7874 -0.4064)
			(end -0.7874 0.4064)
			(stroke
				(width 0.1524)
				(type default)
			)
			(layer "B.SilkS")
		)
		(fp_line
			(start 0.67945 0.3048)
			(end 0.67945 -0.305054)
			(stroke
				(width 0.1)
				(type default)
			)
			(layer "B.Fab")
		)
		(fp_line
			(start 0.67945 -0.305054)
			(end 0.12065 -0.305054)
			(stroke
				(width 0.1)
				(type default)
			)
			(layer "B.Fab")
		)
		(fp_line
			(start 0.12065 0.3048)
			(end 0.67945 0.3048)
			(stroke
				(width 0.1)
				(type default)
			)
			(layer "B.Fab")
		)
		(fp_line
			(start 0.12065 0.2794)
			(end 0.12065 0.3048)
			(stroke
				(width 0.1)
				(type default)
			)
			(layer "B.Fab")
		)
		(fp_line
			(start 0.12065 -0.2794)
			(end -0.12065 -0.2794)
			(stroke
				(width 0.1)
				(type default)
			)
			(layer "B.Fab")
		)
		(fp_line
			(start 0.12065 -0.305054)
			(end 0.12065 -0.2794)
			(stroke
				(width 0.1)
				(type default)
			)
			(layer "B.Fab")
		)
		(fp_line
			(start -0.120396 0.3048)
			(end -0.120396 0.2794)
			(stroke
				(width 0.1)
				(type default)
			)
			(layer "B.Fab")
		)
		(fp_line
			(start -0.120396 0.2794)
			(end 0.12065 0.2794)
			(stroke
				(width 0.1)
				(type default)
			)
			(layer "B.Fab")
		)
		(fp_line
			(start -0.12065 -0.2794)
			(end -0.12065 -0.3048)
			(stroke
				(width 0.1)
				(type default)
			)
			(layer "B.Fab")
		)
		(fp_line
			(start -0.12065 -0.3048)
			(end -0.67945 -0.3048)
			(stroke
				(width 0.1)
				(type default)
			)
			(layer "B.Fab")
		)
		(fp_line
			(start -0.67945 0.3048)
			(end -0.120396 0.3048)
			(stroke
				(width 0.1)
				(type default)
			)
			(layer "B.Fab")
		)
		(fp_line
			(start -0.67945 -0.3048)
			(end -0.67945 0.3048)
			(stroke
				(width 0.1)
				(type default)
			)
			(layer "B.Fab")
		)
		(pad "1" smd circle
			(at 0.40005 0)
			(size 0 0)
			(layers "B.Cu" "B.Mask" "B.Paste")
			(net "M_BMC_DDR4_MA<7>")
		)
		(pad "2" smd circle
			(at -0.40005 0)
			(size 0 0)
			(layers "B.Cu" "B.Mask" "B.Paste")
			(net "P1V2_AUX")
		)
	)
	(footprint ""
		(layer "B.Cu")
		(at 85.29955 -45.443394 180)
		(property "Reference" "R356"
			(at 0 0 0)
			(layer "B.SilkS")
			(hide yes)
			(effects
				(font
					(size 1.27 1.27)
				)
				(justify mirror)
			)
		)
		(property "Value" ""
			(at 0 0 0)
			(layer "B.Fab")
			(effects
				(font
					(size 1.27 1.27)
				)
				(justify mirror)
			)
		)
		(duplicate_pad_numbers_are_jumpers no)
		(fp_line
			(start 0.7874 0.4064)
			(end 0.7874 -0.4064)
			(stroke
				(width 0.1524)
				(type default)
			)
			(layer "B.SilkS")
		)
		(fp_line
			(start 0.7874 -0.4064)
			(end -0.7874 -0.4064)
			(stroke
				(width 0.1524)
				(type default)
			)
			(layer "B.SilkS")
		)
		(fp_line
			(start -0.7874 0.4064)
			(end 0.7874 0.4064)
			(stroke
				(width 0.1524)
				(type default)
			)
			(layer "B.SilkS")
		)
		(fp_line
			(start -0.7874 -0.4064)
			(end -0.7874 0.4064)
			(stroke
				(width 0.1524)
				(type default)
			)
			(layer "B.SilkS")
		)
		(fp_line
			(start 0.67945 0.3048)
			(end 0.67945 -0.305054)
			(stroke
				(width 0.1)
				(type default)
			)
			(layer "B.Fab")
		)
		(fp_line
			(start 0.67945 -0.305054)
			(end 0.12065 -0.305054)
			(stroke
				(width 0.1)
				(type default)
			)
			(layer "B.Fab")
		)
		(fp_line
			(start 0.12065 0.3048)
			(end 0.67945 0.3048)
			(stroke
				(width 0.1)
				(type default)
			)
			(layer "B.Fab")
		)
		(fp_line
			(start 0.12065 0.2794)
			(end 0.12065 0.3048)
			(stroke
				(width 0.1)
				(type default)
			)
			(layer "B.Fab")
		)
		(fp_line
			(start 0.12065 -0.2794)
			(end -0.12065 -0.2794)
			(stroke
				(width 0.1)
				(type default)
			)
			(layer "B.Fab")
		)
		(fp_line
			(start 0.12065 -0.305054)
			(end 0.12065 -0.2794)
			(stroke
				(width 0.1)
				(type default)
			)
			(layer "B.Fab")
		)
		(fp_line
			(start -0.120396 0.3048)
			(end -0.120396 0.2794)
			(stroke
				(width 0.1)
				(type default)
			)
			(layer "B.Fab")
		)
		(fp_line
			(start -0.120396 0.2794)
			(end 0.12065 0.2794)
			(stroke
				(width 0.1)
				(type default)
			)
			(layer "B.Fab")
		)
		(fp_line
			(start -0.12065 -0.2794)
			(end -0.12065 -0.3048)
			(stroke
				(width 0.1)
				(type default)
			)
			(layer "B.Fab")
		)
		(fp_line
			(start -0.12065 -0.3048)
			(end -0.67945 -0.3048)
			(stroke
				(width 0.1)
				(type default)
			)
			(layer "B.Fab")
		)
		(fp_line
			(start -0.67945 0.3048)
			(end -0.120396 0.3048)
			(stroke
				(width 0.1)
				(type default)
			)
			(layer "B.Fab")
		)
		(fp_line
			(start -0.67945 -0.3048)
			(end -0.67945 0.3048)
			(stroke
				(width 0.1)
				(type default)
			)
			(layer "B.Fab")
		)
		(pad "1" smd circle
			(at 0.40005 0)
			(size 0 0)
			(layers "B.Cu" "B.Mask" "B.Paste")
			(net "M_BMC_DDR4_MA<5>")
		)
		(pad "2" smd circle
			(at -0.40005 0)
			(size 0 0)
			(layers "B.Cu" "B.Mask" "B.Paste")
			(net "P1V2_AUX")
		)
	)
	(footprint ""
		(layer "B.Cu")
		(at 27.31135 -86.778846)
		(property "Reference" "R459"
			(at 0 0 0)
			(layer "B.SilkS")
			(hide yes)
			(effects
				(font
					(size 1.27 1.27)
				)
				(justify mirror)
			)
		)
		(property "Value" ""
			(at 0 0 0)
			(layer "B.Fab")
			(effects
				(font
					(size 1.27 1.27)
				)
				(justify mirror)
			)
		)
		(duplicate_pad_numbers_are_jumpers no)
		(fp_line
			(start -0.7874 -0.4064)
			(end -0.7874 0.4064)
			(stroke
				(width 0.1524)
				(type default)
			)
			(layer "B.SilkS")
		)
		(fp_line
			(start -0.7874 0.4064)
			(end 0.7874 0.4064)
			(stroke
				(width 0.1524)
				(type default)
			)
			(layer "B.SilkS")
		)
		(fp_line
			(start 0.7874 -0.4064)
			(end -0.7874 -0.4064)
			(stroke
				(width 0.1524)
				(type default)
			)
			(layer "B.SilkS")
		)
		(fp_line
			(start 0.7874 0.4064)
			(end 0.7874 -0.4064)
			(stroke
				(width 0.1524)
				(type default)
			)
			(layer "B.SilkS")
		)
		(fp_line
			(start -0.67945 -0.3048)
			(end -0.67945 0.3048)
			(stroke
				(width 0.1)
				(type default)
			)
			(layer "B.Fab")
		)
		(fp_line
			(start -0.67945 0.3048)
			(end -0.120396 0.3048)
			(stroke
				(width 0.1)
				(type default)
			)
			(layer "B.Fab")
		)
		(fp_line
			(start -0.12065 -0.3048)
			(end -0.67945 -0.3048)
			(stroke
				(width 0.1)
				(type default)
			)
			(layer "B.Fab")
		)
		(fp_line
			(start -0.12065 -0.2794)
			(end -0.12065 -0.3048)
			(stroke
				(width 0.1)
				(type default)
			)
			(layer "B.Fab")
		)
		(fp_line
			(start -0.120396 0.2794)
			(end 0.12065 0.2794)
			(stroke
				(width 0.1)
				(type default)
			)
			(layer "B.Fab")
		)
		(fp_line
			(start -0.120396 0.3048)
			(end -0.120396 0.2794)
			(stroke
				(width 0.1)
				(type default)
			)
			(layer "B.Fab")
		)
		(fp_line
			(start 0.12065 -0.305054)
			(end 0.12065 -0.2794)
			(stroke
				(width 0.1)
				(type default)
			)
			(layer "B.Fab")
		)
		(fp_line
			(start 0.12065 -0.2794)
			(end -0.12065 -0.2794)
			(stroke
				(width 0.1)
				(type default)
			)
			(layer "B.Fab")
		)
		(fp_line
			(start 0.12065 0.2794)
			(end 0.12065 0.3048)
			(stroke
				(width 0.1)
				(type default)
			)
			(layer "B.Fab")
		)
		(fp_line
			(start 0.12065 0.3048)
			(end 0.67945 0.3048)
			(stroke
				(width 0.1)
				(type default)
			)
			(layer "B.Fab")
		)
		(fp_line
			(start 0.67945 -0.305054)
			(end 0.12065 -0.305054)
			(stroke
				(width 0.1)
				(type default)
			)
			(layer "B.Fab")
		)
		(fp_line
			(start 0.67945 0.3048)
			(end 0.67945 -0.305054)
			(stroke
				(width 0.1)
				(type default)
			)
			(layer "B.Fab")
		)
		(pad "1" smd circle
			(at 0.40005 0 180)
			(size 0 0)
			(layers "B.Cu" "B.Mask" "B.Paste")
			(net "BSM_PRSNT_R_N")
		)
		(pad "2" smd circle
			(at -0.40005 0 180)
			(size 0 0)
			(layers "B.Cu" "B.Mask" "B.Paste")
			(net "BSM_PRSNT_R1_N")
		)
	)
)
